# T6G (Grand Teton) — schematic netlist excerpt (pin names and nets, part order shuffled) for the footprints in the layout excerpt that follows; sources: Cadence DE-HDL packaged netlist, KiCad conversion of 04192023_DAF0TMB3IC0_F0TG_MB_C_brd_V02_OCP.brd

R235  Q_RES  0 5% CHIP  pkg 0402LF  page 82 : A = CPU1_XTRIG_L7 ; B = FM_CPU1_XTRIG_L7
C935  Q_CAP_DIFFBUS  DIFF BUS_0.22UF 6.3V 20% X6S  pkg C0201  page 63 : \1\ = P5E_CPU0_P1_TX_C_DP<15> ; \2\ = P5E_CPU0_P1_TX_DP<15>
R1333  Q_RES  0 5% EMPTY  pkg 0402LF  page 159 : A = I3C_SPD_DDRGL_CPU0_BYPASS_SDA ; B = I3C_SPD_DDRGL_CPU0_SDA

(kicad_pcb
	(version 20260206)
	(generator "pcbnew")
	(generator_version "10.0")
	(general
		(thickness 1.6)
		(legacy_teardrops no)
	)
	(paper "A4")
	(title_block
		(title "04192023_DAF0TMB3IC0_F0TG_MB_C_brd_V02_OCP.brd")
		(comment 1 "Grand Teton / footprints 663-665 of 8354")
	)
	(layers
		(0 "F.Cu" signal "TOP")
		(4 "In1.Cu" signal "GND")
		(6 "In2.Cu" signal "IN1")
		(8 "In3.Cu" signal "GND1")
		(10 "In4.Cu" signal "IN2")
		(12 "In5.Cu" signal "GND2")
		(14 "In6.Cu" signal "IN3")
		(16 "In7.Cu" signal "GND3")
		(18 "In8.Cu" signal "VCC")
		(20 "In9.Cu" signal "VCC1")
		(22 "In10.Cu" signal "GND4")
		(24 "In11.Cu" signal "IN4")
		(26 "In12.Cu" signal "GND5")
		(28 "In13.Cu" signal "IN5")
		(30 "In14.Cu" signal "GND6")
		(32 "In15.Cu" signal "IN6")
		(34 "In16.Cu" signal "GND7")
		(2 "B.Cu" signal "BOTTOM")
		(9 "F.Adhes" user "F.Adhesive")
		(11 "B.Adhes" user "B.Adhesive")
		(13 "F.Paste" user "Package Geometry/Pastemask Top")
		(15 "B.Paste" user "Package Geometry/Pastemask Bottom")
		(5 "F.SilkS" user "Ref Des/Silkscreen Top")
		(7 "B.SilkS" user "Ref Des/Silkscreen Bottom")
		(1 "F.Mask" user "Board Geometry/Soldermask Top")
		(3 "B.Mask" user "Board Geometry/Soldermask Bottom")
		(17 "Dwgs.User" user "User.Drawings")
		(19 "Cmts.User" user "User.Comments")
		(21 "Eco1.User" user "User.Eco1")
		(23 "Eco2.User" user "User.Eco2")
		(25 "Edge.Cuts" user "Board Geometry/Outline")
		(27 "Margin" user)
		(31 "F.CrtYd" user "Package Geometry/Place Bound Top")
		(29 "B.CrtYd" user "Package Geometry/Place Bound Bottom")
		(35 "F.Fab" user "Ref Des/Assembly Top")
		(33 "B.Fab" user "Ref Des/Assembly Bottom")
	)
	(footprint ""
		(layer "F.Cu")
		(at 435.102 -171.4881 -90)
		(property "Reference" "R1333"
			(at 0 0 270)
			(layer "F.SilkS")
			(hide yes)
			(effects
				(font
					(size 1.27 1.27)
				)
			)
		)
		(property "Value" ""
			(at 0 0 270)
			(layer "F.Fab")
			(effects
				(font
					(size 1.27 1.27)
				)
			)
		)
		(duplicate_pad_numbers_are_jumpers no)
		(fp_line
			(start -0.7874 0.4064)
			(end -0.7874 -0.4064)
			(stroke
				(width 0.1524)
				(type default)
			)
			(layer "F.SilkS")
		)
		(fp_line
			(start 0.7874 0.4064)
			(end -0.7874 0.4064)
			(stroke
				(width 0.1524)
				(type default)
			)
			(layer "F.SilkS")
		)
		(fp_line
			(start -0.7874 -0.4064)
			(end 0.7874 -0.4064)
			(stroke
				(width 0.1524)
				(type default)
			)
			(layer "F.SilkS")
		)
		(fp_line
			(start 0.7874 -0.4064)
			(end 0.7874 0.4064)
			(stroke
				(width 0.1524)
				(type default)
			)
			(layer "F.SilkS")
		)
		(fp_line
			(start -0.67945 0.3048)
			(end -0.67945 -0.305054)
			(stroke
				(width 0.1)
				(type default)
			)
			(layer "F.Fab")
		)
		(fp_line
			(start -0.12065 0.3048)
			(end -0.67945 0.3048)
			(stroke
				(width 0.1)
				(type default)
			)
			(layer "F.Fab")
		)
		(fp_line
			(start 0.120396 0.3048)
			(end 0.120396 0.2794)
			(stroke
				(width 0.1)
				(type default)
			)
			(layer "F.Fab")
		)
		(fp_line
			(start 0.67945 0.3048)
			(end 0.120396 0.3048)
			(stroke
				(width 0.1)
				(type default)
			)
			(layer "F.Fab")
		)
		(fp_line
			(start -0.12065 0.2794)
			(end -0.12065 0.3048)
			(stroke
				(width 0.1)
				(type default)
			)
			(layer "F.Fab")
		)
		(fp_line
			(start 0.120396 0.2794)
			(end -0.12065 0.2794)
			(stroke
				(width 0.1)
				(type default)
			)
			(layer "F.Fab")
		)
		(fp_line
			(start -0.12065 -0.2794)
			(end 0.12065 -0.2794)
			(stroke
				(width 0.1)
				(type default)
			)
			(layer "F.Fab")
		)
		(fp_line
			(start 0.12065 -0.2794)
			(end 0.12065 -0.3048)
			(stroke
				(width 0.1)
				(type default)
			)
			(layer "F.Fab")
		)
		(fp_line
			(start 0.12065 -0.3048)
			(end 0.67945 -0.3048)
			(stroke
				(width 0.1)
				(type default)
			)
			(layer "F.Fab")
		)
		(fp_line
			(start 0.67945 -0.3048)
			(end 0.67945 0.3048)
			(stroke
				(width 0.1)
				(type default)
			)
			(layer "F.Fab")
		)
		(fp_line
			(start -0.67945 -0.305054)
			(end -0.12065 -0.305054)
			(stroke
				(width 0.1)
				(type default)
			)
			(layer "F.Fab")
		)
		(fp_line
			(start -0.12065 -0.305054)
			(end -0.12065 -0.2794)
			(stroke
				(width 0.1)
				(type default)
			)
			(layer "F.Fab")
		)
		(pad "1" smd rect
			(at -0.40005 0 90)
			(size 0.4572 0.508)
			(layers "F.Cu" "F.Mask" "F.Paste")
			(net "I3C_SPD_DDRGL_CPU0_BYPASS_SDA")
		)
		(pad "2" smd rect
			(at 0.40005 0 90)
			(size 0.4572 0.508)
			(layers "F.Cu" "F.Mask" "F.Paste")
			(net "I3C_SPD_DDRGL_CPU0_SDA")
		)
	)
	(footprint ""
		(layer "F.Cu")
		(at 178.8922 -96.103948 90)
		(property "Reference" "R235"
			(at 0 0 90)
			(layer "F.SilkS")
			(hide yes)
			(effects
				(font
					(size 1.27 1.27)
				)
			)
		)
		(property "Value" ""
			(at 0 0 90)
			(layer "F.Fab")
			(effects
				(font
					(size 1.27 1.27)
				)
			)
		)
		(duplicate_pad_numbers_are_jumpers no)
		(fp_line
			(start 0.7874 -0.4064)
			(end 0.7874 0.4064)
			(stroke
				(width 0.1524)
				(type default)
			)
			(layer "F.SilkS")
		)
		(fp_line
			(start -0.7874 -0.4064)
			(end 0.7874 -0.4064)
			(stroke
				(width 0.1524)
				(type default)
			)
			(layer "F.SilkS")
		)
		(fp_line
			(start 0.7874 0.4064)
			(end -0.7874 0.4064)
			(stroke
				(width 0.1524)
				(type default)
			)
			(layer "F.SilkS")
		)
		(fp_line
			(start -0.7874 0.4064)
			(end -0.7874 -0.4064)
			(stroke
				(width 0.1524)
				(type default)
			)
			(layer "F.SilkS")
		)
		(fp_line
			(start -0.12065 -0.305054)
			(end -0.12065 -0.2794)
			(stroke
				(width 0.1)
				(type default)
			)
			(layer "F.Fab")
		)
		(fp_line
			(start -0.67945 -0.305054)
			(end -0.12065 -0.305054)
			(stroke
				(width 0.1)
				(type default)
			)
			(layer "F.Fab")
		)
		(fp_line
			(start 0.67945 -0.3048)
			(end 0.67945 0.3048)
			(stroke
				(width 0.1)
				(type default)
			)
			(layer "F.Fab")
		)
		(fp_line
			(start 0.12065 -0.3048)
			(end 0.67945 -0.3048)
			(stroke
				(width 0.1)
				(type default)
			)
			(layer "F.Fab")
		)
		(fp_line
			(start 0.12065 -0.2794)
			(end 0.12065 -0.3048)
			(stroke
				(width 0.1)
				(type default)
			)
			(layer "F.Fab")
		)
		(fp_line
			(start -0.12065 -0.2794)
			(end 0.12065 -0.2794)
			(stroke
				(width 0.1)
				(type default)
			)
			(layer "F.Fab")
		)
		(fp_line
			(start 0.120396 0.2794)
			(end -0.12065 0.2794)
			(stroke
				(width 0.1)
				(type default)
			)
			(layer "F.Fab")
		)
		(fp_line
			(start -0.12065 0.2794)
			(end -0.12065 0.3048)
			(stroke
				(width 0.1)
				(type default)
			)
			(layer "F.Fab")
		)
		(fp_line
			(start 0.67945 0.3048)
			(end 0.120396 0.3048)
			(stroke
				(width 0.1)
				(type default)
			)
			(layer "F.Fab")
		)
		(fp_line
			(start 0.120396 0.3048)
			(end 0.120396 0.2794)
			(stroke
				(width 0.1)
				(type default)
			)
			(layer "F.Fab")
		)
		(fp_line
			(start -0.12065 0.3048)
			(end -0.67945 0.3048)
			(stroke
				(width 0.1)
				(type default)
			)
			(layer "F.Fab")
		)
		(fp_line
			(start -0.67945 0.3048)
			(end -0.67945 -0.305054)
			(stroke
				(width 0.1)
				(type default)
			)
			(layer "F.Fab")
		)
		(pad "1" smd circle
			(at -0.40005 0 90)
			(size 0 0)
			(layers "F.Cu" "F.Mask" "F.Paste")
			(net "CPU1_XTRIG_L7")
		)
		(pad "2" smd circle
			(at 0.40005 0 90)
			(size 0 0)
			(layers "F.Cu" "F.Mask" "F.Paste")
			(net "FM_CPU1_XTRIG_L7")
		)
	)
	(footprint ""
		(layer "F.Cu")
		(at 358.268524 -387.853428)
		(property "Reference" "C935"
			(at 0 0 0)
			(layer "F.SilkS")
			(hide yes)
			(effects
				(font
					(size 1.27 1.27)
				)
			)
		)
		(property "Value" ""
			(at 0 0 0)
			(layer "F.Fab")
			(effects
				(font
					(size 1.27 1.27)
				)
			)
		)
		(duplicate_pad_numbers_are_jumpers no)
		(fp_line
			(start -0.299974 -0.150114)
			(end 0.299974 -0.150114)
			(stroke
				(width 0.1)
				(type default)
			)
			(layer "F.Fab")
		)
		(fp_line
			(start -0.299974 0.150114)
			(end -0.299974 -0.150114)
			(stroke
				(width 0.1)
				(type default)
			)
			(layer "F.Fab")
		)
		(fp_line
			(start 0.299974 -0.150114)
			(end 0.299974 0.150114)
			(stroke
				(width 0.1)
				(type default)
			)
			(layer "F.Fab")
		)
		(fp_line
			(start 0.299974 0.150114)
			(end -0.299974 0.150114)
			(stroke
				(width 0.1)
				(type default)
			)
			(layer "F.Fab")
		)
		(pad "1" smd rect
			(at -0.2667 0)
			(size 0.3048 0.381)
			(layers "F.Cu" "F.Mask" "F.Paste")
			(net "P5E_CPU0_P1_TX_C_DP<15>")
		)
		(pad "2" smd rect
			(at 0.2667 0)
			(size 0.3048 0.381)
			(layers "F.Cu" "F.Mask" "F.Paste")
			(net "P5E_CPU0_P1_TX_DP<15>")
		)
	)
)
